(kicad_pcb
	(version 20260206)
	(generator "pcbnew")
	(generator_version "10.0")
	(general
		(thickness 1.6)
		(legacy_teardrops no)
	)
	(paper "A4")
	(title_block
		(title "12092022_DA0F0TFB6D0_F0T_FAN_BOARD_MP5048_D_brd_v02_OCP.brd")
		(comment 1 "Grand Teton / footprints 747-750 of 924")
	)
	(layers
		(0 "F.Cu" signal "TOP")
		(4 "In1.Cu" signal "GND")
		(6 "In2.Cu" signal "IN1")
		(8 "In3.Cu" signal "IN2")
		(10 "In4.Cu" signal "GND1")
		(2 "B.Cu" signal "BOTTOM")
		(9 "F.Adhes" user "F.Adhesive")
		(11 "B.Adhes" user "B.Adhesive")
		(13 "F.Paste" user "Package Geometry/Pastemask Top")
		(15 "B.Paste" user "Package Geometry/Pastemask Bottom")
		(5 "F.SilkS" user "Ref Des/Silkscreen Top")
		(7 "B.SilkS" user "Ref Des/Silkscreen Bottom")
		(1 "F.Mask" user "Board Geometry/Soldermask Top")
		(3 "B.Mask" user "Board Geometry/Soldermask Bottom")
		(17 "Dwgs.User" user "User.Drawings")
		(19 "Cmts.User" user "User.Comments")
		(21 "Eco1.User" user "User.Eco1")
		(23 "Eco2.User" user "User.Eco2")
		(25 "Edge.Cuts" user "Board Geometry/Outline")
		(27 "Margin" user)
		(31 "F.CrtYd" user "Package Geometry/Place Bound Top")
		(29 "B.CrtYd" user "Package Geometry/Place Bound Bottom")
		(35 "F.Fab" user "Ref Des/Assembly Top")
		(33 "B.Fab" user "Ref Des/Assembly Bottom")
	)
	(footprint ""
		(layer "B.Cu")
		(at 5.38099 -78.416912 -90)
		(property "Reference" "PD16"
			(at -2.736088 -3.73634 270)
			(unlocked yes)
			(layer "B.SilkS")
			(effects
				(font
					(size 0.7874 0.5842)
					(thickness 0.1524)
				)
				(justify left mirror)
			)
		)
		(property "Value" ""
			(at 0 0 90)
			(layer "B.Fab")
			(effects
				(font
					(size 1.27 1.27)
				)
				(justify mirror)
			)
		)
		(duplicate_pad_numbers_are_jumpers no)
		(fp_line
			(start -5.536184 3.109976)
			(end -5.536184 -3.109976)
			(stroke
				(width 0.1524)
				(type default)
			)
			(layer "B.SilkS")
		)
		(fp_line
			(start 4.647184 3.109976)
			(end -5.536184 3.109976)
			(stroke
				(width 0.1524)
				(type default)
			)
			(layer "B.SilkS")
		)
		(fp_line
			(start 0.635 0.635)
			(end -0.635 -0.127)
			(stroke
				(width 0.1524)
				(type default)
			)
			(layer "B.SilkS")
		)
		(fp_line
			(start -0.635 -0.127)
			(end -1.397 -0.127)
			(stroke
				(width 0.1524)
				(type default)
			)
			(layer "B.SilkS")
		)
		(fp_line
			(start -0.635 -0.127)
			(end 0.635 -0.889)
			(stroke
				(width 0.1524)
				(type default)
			)
			(layer "B.SilkS")
		)
		(fp_line
			(start 1.397 -0.127)
			(end 0.635 -0.127)
			(stroke
				(width 0.1524)
				(type default)
			)
			(layer "B.SilkS")
		)
		(fp_line
			(start 0.635 -0.889)
			(end 0.635 0.635)
			(stroke
				(width 0.1524)
				(type default)
			)
			(layer "B.SilkS")
		)
		(fp_line
			(start -0.762 -1.143)
			(end -0.762 0.889)
			(stroke
				(width 0.1524)
				(type default)
			)
			(layer "B.SilkS")
		)
		(fp_line
			(start -5.536184 -3.109976)
			(end 4.647184 -3.109976)
			(stroke
				(width 0.1524)
				(type default)
			)
			(layer "B.SilkS")
		)
		(fp_line
			(start 4.647184 -3.109976)
			(end 4.647184 3.109976)
			(stroke
				(width 0.1524)
				(type default)
			)
			(layer "B.SilkS")
		)
		(fp_poly
			(pts
				(xy -5.5118 -3.0988) (xy -5.5118 3.1496) (xy -4.572 3.1496) (xy -4.572 -3.0988)
			)
			(stroke
				(width 0)
				(type default)
			)
			(fill yes)
			(layer "B.SilkS")
		)
		(fp_line
			(start -3.554984 3.109976)
			(end -3.554984 -3.109976)
			(stroke
				(width 0.1)
				(type default)
			)
			(layer "B.Fab")
		)
		(fp_line
			(start 3.554984 3.109976)
			(end -3.554984 3.109976)
			(stroke
				(width 0.1)
				(type default)
			)
			(layer "B.Fab")
		)
		(fp_line
			(start -3.554984 -3.109976)
			(end 3.554984 -3.109976)
			(stroke
				(width 0.1)
				(type default)
			)
			(layer "B.Fab")
		)
		(fp_line
			(start 3.554984 -3.109976)
			(end 3.554984 3.109976)
			(stroke
				(width 0.1)
				(type default)
			)
			(layer "B.Fab")
		)
		(fp_text user "-"
			(at -5.403088 2.36474 270)
			(unlocked yes)
			(layer "B.SilkS")
			(effects
				(font
					(size 1.905 1.4224)
					(thickness 0.1524)
				)
				(justify left mirror)
			)
		)
		(fp_text user "+"
			(at 7.169912 -0.55626 270)
			(unlocked yes)
			(layer "B.SilkS")
			(effects
				(font
					(size 1.905 1.4224)
					(thickness 0.1524)
				)
				(justify left mirror)
			)
		)
		(fp_text user "+"
			(at 6.1214 -0.32385 270)
			(unlocked yes)
			(layer "B.Fab")
			(effects
				(font
					(size 1.905 1.4224)
					(thickness 0.1524)
				)
				(justify left mirror)
			)
		)
		(fp_text user "-"
			(at -5.334 -0.34925 270)
			(unlocked yes)
			(layer "B.Fab")
			(effects
				(font
					(size 1.905 1.4224)
					(thickness 0.1524)
				)
				(justify left mirror)
			)
		)
		(pad "A" smd rect
			(at 3.299968 0 90)
			(size 2.413 3.302)
			(layers "B.Cu" "B.Mask" "B.Paste")
			(net "GND")
		)
		(pad "C" smd rect
			(at -3.299968 0 90)
			(size 2.413 3.302)
			(layers "B.Cu" "B.Mask" "B.Paste")
			(net "P52V_HSC")
		)
	)
	(footprint ""
		(layer "B.Cu")
		(at 3.683 -249.428 -90)
		(property "Reference" "PC52"
			(at 0 0 90)
			(layer "B.SilkS")
			(hide yes)
			(effects
				(font
					(size 1.27 1.27)
				)
				(justify mirror)
			)
		)
		(property "Value" ""
			(at 0 0 90)
			(layer "B.Fab")
			(effects
				(font
					(size 1.27 1.27)
				)
				(justify mirror)
			)
		)
		(duplicate_pad_numbers_are_jumpers no)
		(fp_line
			(start -0.7874 0.4064)
			(end 0.7874 0.4064)
			(stroke
				(width 0.1524)
				(type default)
			)
			(layer "B.SilkS")
		)
		(fp_line
			(start 0.7874 0.4064)
			(end 0.7874 -0.4064)
			(stroke
				(width 0.1524)
				(type default)
			)
			(layer "B.SilkS")
		)
		(fp_line
			(start -0.7874 -0.4064)
			(end -0.7874 0.4064)
			(stroke
				(width 0.1524)
				(type default)
			)
			(layer "B.SilkS")
		)
		(fp_line
			(start 0.7874 -0.4064)
			(end -0.7874 -0.4064)
			(stroke
				(width 0.1524)
				(type default)
			)
			(layer "B.SilkS")
		)
		(fp_line
			(start -0.67945 0.3048)
			(end -0.120396 0.3048)
			(stroke
				(width 0.1)
				(type default)
			)
			(layer "B.Fab")
		)
		(fp_line
			(start -0.120396 0.3048)
			(end -0.120396 0.2794)
			(stroke
				(width 0.1)
				(type default)
			)
			(layer "B.Fab")
		)
		(fp_line
			(start 0.12065 0.3048)
			(end 0.67945 0.3048)
			(stroke
				(width 0.1)
				(type default)
			)
			(layer "B.Fab")
		)
		(fp_line
			(start 0.67945 0.3048)
			(end 0.67945 -0.305054)
			(stroke
				(width 0.1)
				(type default)
			)
			(layer "B.Fab")
		)
		(fp_line
			(start -0.120396 0.2794)
			(end 0.12065 0.2794)
			(stroke
				(width 0.1)
				(type default)
			)
			(layer "B.Fab")
		)
		(fp_line
			(start 0.12065 0.2794)
			(end 0.12065 0.3048)
			(stroke
				(width 0.1)
				(type default)
			)
			(layer "B.Fab")
		)
		(fp_line
			(start -0.12065 -0.2794)
			(end -0.12065 -0.3048)
			(stroke
				(width 0.1)
				(type default)
			)
			(layer "B.Fab")
		)
		(fp_line
			(start 0.12065 -0.2794)
			(end -0.12065 -0.2794)
			(stroke
				(width 0.1)
				(type default)
			)
			(layer "B.Fab")
		)
		(fp_line
			(start -0.67945 -0.3048)
			(end -0.67945 0.3048)
			(stroke
				(width 0.1)
				(type default)
			)
			(layer "B.Fab")
		)
		(fp_line
			(start -0.12065 -0.3048)
			(end -0.67945 -0.3048)
			(stroke
				(width 0.1)
				(type default)
			)
			(layer "B.Fab")
		)
		(fp_line
			(start 0.12065 -0.305054)
			(end 0.12065 -0.2794)
			(stroke
				(width 0.1)
				(type default)
			)
			(layer "B.Fab")
		)
		(fp_line
			(start 0.67945 -0.305054)
			(end 0.12065 -0.305054)
			(stroke
				(width 0.1)
				(type default)
			)
			(layer "B.Fab")
		)
		(pad "1" smd circle
			(at 0.40005 0 90)
			(size 0 0)
			(layers "B.Cu" "B.Mask" "B.Paste")
			(net "FAN_6_SS")
		)
		(pad "2" smd circle
			(at -0.40005 0 90)
			(size 0 0)
			(layers "B.Cu" "B.Mask" "B.Paste")
			(net "GND")
		)
	)
	(footprint ""
		(layer "B.Cu")
		(at -14.841474 -209.296)
		(property "Reference" "J95"
			(at 3.5052 -5.552948 0)
			(unlocked yes)
			(layer "B.SilkS")
			(effects
				(font
					(size 0.7874 0.5842)
					(thickness 0.1524)
				)
				(justify left mirror)
			)
		)
		(property "Value" ""
			(at 0 0 0)
			(layer "B.Fab")
			(effects
				(font
					(size 1.27 1.27)
				)
				(justify mirror)
			)
		)
		(duplicate_pad_numbers_are_jumpers no)
		(fp_line
			(start -3.330702 -4.771136)
			(end 0 4.011168)
			(stroke
				(width 0.1524)
				(type default)
			)
			(layer "B.SilkS")
		)
		(fp_line
			(start 0 4.011168)
			(end 3.330702 -4.771136)
			(stroke
				(width 0.1524)
				(type default)
			)
			(layer "B.SilkS")
		)
		(fp_line
			(start 3.330702 -4.771136)
			(end -3.330702 -4.771136)
			(stroke
				(width 0.1524)
				(type default)
			)
			(layer "B.SilkS")
		)
		(fp_line
			(start -3.330702 -4.771136)
			(end 0 4.011168)
			(stroke
				(width 0.1)
				(type default)
			)
			(layer "B.Fab")
		)
		(fp_line
			(start 0 4.011168)
			(end 3.330702 -4.771136)
			(stroke
				(width 0.1)
				(type default)
			)
			(layer "B.Fab")
		)
		(fp_line
			(start 3.330702 -4.771136)
			(end -3.330702 -4.771136)
			(stroke
				(width 0.1)
				(type default)
			)
			(layer "B.Fab")
		)
		(pad "1" thru_hole circle
			(at 0 0 180)
			(size 2.159 2.159)
			(drill 1.7018)
			(layers "*.Cu" "*.Mask")
			(remove_unused_layers no)
			(net "GND2")
			(clearance 0.0254)
			(thermal_gap 0.0254)
		)
		(pad "2" thru_hole circle
			(at 1.27 -3.348736 180)
			(size 2.159 2.159)
			(drill 1.7018)
			(layers "*.Cu" "*.Mask")
			(remove_unused_layers no)
			(net "TDR_SE_50_OHM_BOT")
			(clearance 0.0254)
			(thermal_gap 0.0254)
		)
		(pad "3" thru_hole circle
			(at -1.27 -3.348736 180)
			(size 2.159 2.159)
			(drill 1.7018)
			(layers "*.Cu" "*.Mask")
			(remove_unused_layers no)
			(net "TDR_SE_50_OHM_BOT")
			(clearance 0.0254)
			(thermal_gap 0.0254)
		)
	)
	(footprint ""
		(layer "B.Cu")
		(at 16.383 -258.572 90)
		(property "Reference" "PC59"
			(at 0 0 90)
			(layer "B.SilkS")
			(hide yes)
			(effects
				(font
					(size 1.27 1.27)
				)
				(justify mirror)
			)
		)
		(property "Value" ""
			(at 0 0 90)
			(layer "B.Fab")
			(effects
				(font
					(size 1.27 1.27)
				)
				(justify mirror)
			)
		)
		(duplicate_pad_numbers_are_jumpers no)
		(fp_line
			(start 0.7874 -0.4064)
			(end -0.7874 -0.4064)
			(stroke
				(width 0.1524)
				(type default)
			)
			(layer "B.SilkS")
		)
		(fp_line
			(start -0.7874 -0.4064)
			(end -0.7874 0.4064)
			(stroke
				(width 0.1524)
				(type default)
			)
			(layer "B.SilkS")
		)
		(fp_line
			(start 0.7874 0.4064)
			(end 0.7874 -0.4064)
			(stroke
				(width 0.1524)
				(type default)
			)
			(layer "B.SilkS")
		)
		(fp_line
			(start -0.7874 0.4064)
			(end 0.7874 0.4064)
			(stroke
				(width 0.1524)
				(type default)
			)
			(layer "B.SilkS")
		)
		(fp_line
			(start 0.67945 -0.305054)
			(end 0.12065 -0.305054)
			(stroke
				(width 0.1)
				(type default)
			)
			(layer "B.Fab")
		)
		(fp_line
			(start 0.12065 -0.305054)
			(end 0.12065 -0.2794)
			(stroke
				(width 0.1)
				(type default)
			)
			(layer "B.Fab")
		)
		(fp_line
			(start -0.12065 -0.3048)
			(end -0.67945 -0.3048)
			(stroke
				(width 0.1)
				(type default)
			)
			(layer "B.Fab")
		)
		(fp_line
			(start -0.67945 -0.3048)
			(end -0.67945 0.3048)
			(stroke
				(width 0.1)
				(type default)
			)
			(layer "B.Fab")
		)
		(fp_line
			(start 0.12065 -0.2794)
			(end -0.12065 -0.2794)
			(stroke
				(width 0.1)
				(type default)
			)
			(layer "B.Fab")
		)
		(fp_line
			(start -0.12065 -0.2794)
			(end -0.12065 -0.3048)
			(stroke
				(width 0.1)
				(type default)
			)
			(layer "B.Fab")
		)
		(fp_line
			(start 0.12065 0.2794)
			(end 0.12065 0.3048)
			(stroke
				(width 0.1)
				(type default)
			)
			(layer "B.Fab")
		)
		(fp_line
			(start -0.120396 0.2794)
			(end 0.12065 0.2794)
			(stroke
				(width 0.1)
				(type default)
			)
			(layer "B.Fab")
		)
		(fp_line
			(start 0.67945 0.3048)
			(end 0.67945 -0.305054)
			(stroke
				(width 0.1)
				(type default)
			)
			(layer "B.Fab")
		)
		(fp_line
			(start 0.12065 0.3048)
			(end 0.67945 0.3048)
			(stroke
				(width 0.1)
				(type default)
			)
			(layer "B.Fab")
		)
		(fp_line
			(start -0.120396 0.3048)
			(end -0.120396 0.2794)
			(stroke
				(width 0.1)
				(type default)
			)
			(layer "B.Fab")
		)
		(fp_line
			(start -0.67945 0.3048)
			(end -0.120396 0.3048)
			(stroke
				(width 0.1)
				(type default)
			)
			(layer "B.Fab")
		)
		(pad "1" smd circle
			(at 0.40005 0 270)
			(size 0 0)
			(layers "B.Cu" "B.Mask" "B.Paste")
			(net "FAN_7_TIMER")
		)
		(pad "2" smd circle
			(at -0.40005 0 270)
			(size 0 0)
			(layers "B.Cu" "B.Mask" "B.Paste")
			(net "GND")
		)
	)
)
